# S9S_MB_2U (Grand Teton) — schematic netlist excerpt (pin names and nets, part order shuffled) for the footprints in the layout excerpt that follows; sources: Cadence DE-HDL packaged netlist, KiCad conversion of 03242023_DA0F0TMBIJ0_F0T_Motherboard_J_brd_V01_OCP.brd

J11  SCONN288_ADR50017P130CC  SCONN288_ADR50017-P130CC IO  pkg DDR288S_1-1VXB  page 92
  VIN_BULK0  = P12V_S3_AUX_CPU0_NVDIMM
  RFU0  = TP_CHF_CPU0_DIMM1_FRU_0
  VIN_MGMT  = P3V3_AUX
  HSCL  = I3C_SPD_DDREFGH_CPU0_LVC1_SCL_2
  HSDA  = I3C_SPD_DDREFGH_CPU0_LVC1_SDA
  VSS0  = GND
  DQ0_A  = M_F_CPU0_SA_DQ<0>
  VSS1  = GND
  DQ1_A  = M_F_CPU0_SA_DQ<1>
  VSS2  = GND
  DQS0_A_T  = M_F_CPU0_SA_DQS_DP<0>
  DQS0_A_C  = M_F_CPU0_SA_DQS_DN<0>
  VSS3  = GND
  DQ4_A  = M_F_CPU0_SA_DQ<4>
  VSS4  = GND
  DQ5_A  = M_F_CPU0_SA_DQ<5>
  VSS5  = GND
  DQ8_A  = M_F_CPU0_SA_DQ<8>
  VSS6  = GND
  DQ9_A  = M_F_CPU0_SA_DQ<9>
  VSS7  = GND
  DQS1_A_T  = M_F_CPU0_SA_DQS_DP<1>
  DQS1_A_C  = M_F_CPU0_SA_DQS_DN<1>
  VSS8  = GND
  DQ12_A  = M_F_CPU0_SA_DQ<12>
  VSS9  = GND
  DQ13_A  = M_F_CPU0_SA_DQ<13>
  VSS10  = GND
  DQ16_A  = M_F_CPU0_SA_DQ<16>
  VSS11  = GND
  DQ17_A  = M_F_CPU0_SA_DQ<17>
  VSS12  = GND
  DQS2_A_T  = M_F_CPU0_SA_DQS_DP<2>
  DQS2_A_C  = M_F_CPU0_SA_DQS_DN<2>
  VSS13  = GND
  DQ20_A  = M_F_CPU0_SA_DQ<20>
  VSS14  = GND
  DQ21_A  = M_F_CPU0_SA_DQ<21>
  VSS15  = GND
  DQ24_A  = M_F_CPU0_SA_DQ<24>
  VSS16  = GND
  DQ25_A  = M_F_CPU0_SA_DQ<25>
  VSS17  = GND
  DQS3_A_T  = M_F_CPU0_SA_DQS_DP<3>
  DQS3_A_C  = M_F_CPU0_SA_DQS_DN<3>
  VSS18  = GND
  DQ28_A  = M_F_CPU0_SA_DQ<28>
  VSS19  = GND
  DQ29_A  = M_F_CPU0_SA_DQ<29>
  VSS20  = GND
  CB0_A  = M_F_CPU0_SA_CB<0>
  VSS21  = GND
  CB1_A  = M_F_CPU0_SA_CB<1>
  VSS22  = GND
  DQS4_A_T  = M_F_CPU0_SA_DQS_DP<4>
  DQS4_A_C  = M_F_CPU0_SA_DQS_DN<4>
  VSS23  = GND
  CB4_A  = M_F_CPU0_SA_CB<4>
  VSS24  = GND
  CB5_A  = M_F_CPU0_SA_CB<5>
  VSS25  = GND
  ALERT_N  = M_F_CPU0_ALERT_N
  VSS26  = GND
  CS0_A_N  = M_F_CPU0_SA_CS_N<0>
  VSS27  = GND
  CA0_A  = M_F_CPU0_SA_CA<0>
  VSS28  = GND
  CA2_A  = M_F_CPU0_SA_CA<2>
  VSS29  = GND
  CA4_A  = M_F_CPU0_SA_CA<4>
  VSS30  = GND
  CA6_A  = M_F_CPU0_SA_CA<6>
  VSS31  = GND
  PAR_A  = M_F_CPU0_SA_PAR
  VSS32  = GND
  CA0_B  = M_F_CPU0_SB_CA<0>
  VSS33  = GND
  CA2_B  = M_F_CPU0_SB_CA<2>
  VSS34  = GND
  CA4_B  = M_F_CPU0_SB_CA<4>
  VSS35  = GND
  CA6_B  = M_F_CPU0_SB_CA<6>
  VSS36  = GND
  CS0_B_N  = M_F_CPU0_SB_CS_N<0>
  VSS37  = GND
  \lbd||rsp_a_n\  = M_F_CPU0_SA_RSP<0>
  \lbs||rsp_b_n\  = M_F_CPU0_SB_RSP<0>
  VSS38  = GND
  CB4_B  = M_F_CPU0_SB_CB<4>
  VSS39  = GND
  CB5_B  = M_F_CPU0_SB_CB<5>
  VSS40  = GND
  \dqs9_b_t||tdqs9_b_t||dbi4_b_n\  = M_F_CPU0_SB_DQS_DP<9>
  \dqs9_b_c||tdqs9_b_c\  = M_F_CPU0_SB_DQS_DN<9>
  VSS41  = GND
  CB0_B  = M_F_CPU0_SB_CB<0>
  VSS42  = GND
  CB1_B  = M_F_CPU0_SB_CB<1>
  VSS43  = GND
  DQ0_B  = M_F_CPU0_SB_DQ<0>
  VSS44  = GND
  DQ1_B  = M_F_CPU0_SB_DQ<1>
  VSS45  = GND
  DQS0_B_T  = M_F_CPU0_SB_DQS_DP<0>
  DQS0_B_C  = M_F_CPU0_SB_DQS_DN<0>
  VSS46  = GND
  DQ4_B  = M_F_CPU0_SB_DQ<4>
  VSS47  = GND
  DQ5_B  = M_F_CPU0_SB_DQ<5>
  VSS48  = GND
  DQ8_B  = M_F_CPU0_SB_DQ<8>
  VSS49  = GND
  DQ9_B  = M_F_CPU0_SB_DQ<9>
  VSS50  = GND
  DQS1_B_T  = M_F_CPU0_SB_DQS_DP<1>
  DQS1_B_C  = M_F_CPU0_SB_DQS_DN<1>
  VSS51  = GND
  DQ12_B  = M_F_CPU0_SB_DQ<12>
  VSS52  = GND
  DQ13_B  = M_F_CPU0_SB_DQ<13>
  VSS53  = GND
  DQ16_B  = M_F_CPU0_SB_DQ<16>
  VSS54  = GND
  DQ17_B  = M_F_CPU0_SB_DQ<17>
  VSS55  = GND
  DQS2_B_T  = M_F_CPU0_SB_DQS_DP<2>
  DQS2_B_C  = M_F_CPU0_SB_DQS_DN<2>
  VSS56  = GND
  DQ20_B  = M_F_CPU0_SB_DQ<20>
  VSS57  = GND
  DQ21_B  = M_F_CPU0_SB_DQ<21>
  VSS58  = GND
  DQ24_B  = M_F_CPU0_SB_DQ<24>
  VSS59  = GND
  DQ25_B  = M_F_CPU0_SB_DQ<25>
  VSS60  = GND
  DQS3_B_T  = M_F_CPU0_SB_DQS_DP<3>
  DQS3_B_C  = M_F_CPU0_SB_DQS_DN<3>
  VSS61  = GND
  DQ28_B  = M_F_CPU0_SB_DQ<28>
  VSS62  = GND
  DQ29_B  = M_F_CPU0_SB_DQ<29>
  VSS63  = GND
  RFU1  = TP_CHF_CPU0_DIMM1_FRU_1
  VIN_BULK1  = P12V_S3_AUX_CPU0_NVDIMM
  VIN_BULK2  = P12V_S3_AUX_CPU0_NVDIMM
  \pwr_good||fail_n\  = PWRGD_CHF_CPU0_DIMM1
  HSA  = PD_CHF_CPU0_DIMM1_SAA
  RFU2  = TP_CHF_CPU0_DIMM1_FRU_2
  RFU3  = TP_CHF_CPU0_DIMM1_FRU_3
  VSS64  = GND
  DQ2_A  = M_F_CPU0_SA_DQ<2>
  VSS65  = GND
  DQ3_A  = M_F_CPU0_SA_DQ<3>
  VSS66  = GND
  \dqs5_a_c||tdqs5_a_c||dqs5_a_t||tdqs5_a_t\  = M_F_CPU0_SA_DQS_DN<5>
  \dqs5_a_t||tdqs5_a_t\  = M_F_CPU0_SA_DQS_DP<5>
  VSS67  = GND
  DQ6_A  = M_F_CPU0_SA_DQ<6>
  VSS68  = GND
  DQ7_A  = M_F_CPU0_SA_DQ<7>
  VSS69  = GND
  DQ10_A  = M_F_CPU0_SA_DQ<10>
  VSS70  = GND
  DQ11_A  = M_F_CPU0_SA_DQ<11>
  VSS71  = GND
  \dqs6_a_c||tdqs6_a_c||dqs6_a_t||tdqs6_a_t\  = M_F_CPU0_SA_DQS_DN<6>
  \dqs6_a_t||tdqs6_a_t\  = M_F_CPU0_SA_DQS_DP<6>
  VSS72  = GND
  DQ14_A  = M_F_CPU0_SA_DQ<14>
  VSS73  = GND
  DQ15_A  = M_F_CPU0_SA_DQ<15>
  VSS74  = GND
  DQ18_A  = M_F_CPU0_SA_DQ<18>
  VSS75  = GND
  DQ19_A  = M_F_CPU0_SA_DQ<19>
  VSS76  = GND
  \dqs7_a_c||tdqs7_a_c\  = M_F_CPU0_SA_DQS_DN<7>
  \dqs7_a_t||tdqs7_a_t\  = M_F_CPU0_SA_DQS_DP<7>
  VSS77  = GND
  DQ22_A  = M_F_CPU0_SA_DQ<22>
  VSS78  = GND
  DQ23_A  = M_F_CPU0_SA_DQ<23>
  VSS79  = GND
  DQ26_A  = M_F_CPU0_SA_DQ<26>
  VSS80  = GND
  DQ27_A  = M_F_CPU0_SA_DQ<27>
  VSS81  = GND
  \dqs8_a_c||tdqs8_a_c\  = M_F_CPU0_SA_DQS_DN<8>
  \dqs8_a_t||tdqs8_a_t\  = M_F_CPU0_SA_DQS_DP<8>
  VSS82  = GND
  DQ30_A  = M_F_CPU0_SA_DQ<30>
  VSS83  = GND
  DQ31_A  = M_F_CPU0_SA_DQ<31>
  VSS84  = GND
  CB2_A  = M_F_CPU0_SA_CB<2>
  VSS85  = GND
  CB3_A  = M_F_CPU0_SA_CB<3>
  VSS86  = GND
  \dqs9_a_c||tdqs9_a_c\  = M_F_CPU0_SA_DQS_DN<9>
  \dqs9_a_t||tdqs9_a_t\  = M_F_CPU0_SA_DQS_DP<9>
  VSS87  = GND
  CB6_A  = M_F_CPU0_SA_CB<6>
  VSS88  = GND
  CB7_A  = M_F_CPU0_SA_CB<7>
  VSS89  = GND
  RESET_N  = RST_M_EF_CPU0_FPGA_N
  VSS90  = GND
  CS1_A_N  = M_F_CPU0_SA_CS_N<1>
  VSS91  = GND
  CA1_A  = M_F_CPU0_SA_CA<1>
  VSS92  = GND
  CA3_A  = M_F_CPU0_SA_CA<3>
  VSS93  = GND
  CA5_A  = M_F_CPU0_SA_CA<5>
  VSS94  = GND
  CK_T  = M_F_CPU0_CLK_DP<0>
  CK_C  = M_F_CPU0_CLK_DN<0>
  VSS95  = GND
  RFU4  = TP_CHF_CPU0_DIMM1_FRU_4
  CA1_B  = M_F_CPU0_SB_CA<1>
  VSS96  = GND
  CA3_B  = M_F_CPU0_SB_CA<3>
  VSS97  = GND
  CA5_B  = M_F_CPU0_SB_CA<5>
  VSS98  = GND
  PAR_B  = M_F_CPU0_SB_PAR
  VSS99  = GND
  CS1_B_N  = M_F_CPU0_SB_CS_N<1>
  VSS100  = GND
  RFU5  = TP_CHF_CPU0_DIMM1_FRU_5
  RFU6  = TP_CHF_CPU0_DIMM1_FRU_6
  VSS101  = GND
  CB6_B  = M_F_CPU0_SB_CB<6>
  VSS102  = GND
  CB7_B  = M_F_CPU0_SB_CB<7>
  VSS103  = GND
  DQS4_B_C  = M_F_CPU0_SB_DQS_DN<4>
  DQS4_B_T  = M_F_CPU0_SB_DQS_DP<4>
  VSS104  = GND
  CB2_B  = M_F_CPU0_SB_CB<2>
  VSS105  = GND
  CB3_B  = M_F_CPU0_SB_CB<3>
  VSS106  = GND
  DQ2_B  = M_F_CPU0_SB_DQ<2>
  VSS107  = GND
  DQ3_B  = M_F_CPU0_SB_DQ<3>
  VSS108  = GND
  \dqs5_b_c||tdqs5_b_c\  = M_F_CPU0_SB_DQS_DN<5>
  \dqs5_b_t||tdqs5_b_t\  = M_F_CPU0_SB_DQS_DP<5>
  VSS109  = GND
  DQ6_B  = M_F_CPU0_SB_DQ<6>
  VSS110  = GND
  DQ7_B  = M_F_CPU0_SB_DQ<7>
  VSS111  = GND
  DQ10_B  = M_F_CPU0_SB_DQ<10>
  VSS112  = GND
  DQ11_B  = M_F_CPU0_SB_DQ<11>
  VSS113  = GND
  \dqs6_b_c||tdqs6_b_c\  = M_F_CPU0_SB_DQS_DN<6>
  \dqs6_b_t||tdqs6_b_t\  = M_F_CPU0_SB_DQS_DP<6>
  VSS114  = GND
  DQ14_B  = M_F_CPU0_SB_DQ<14>
  VSS115  = GND
  DQ15_B  = M_F_CPU0_SB_DQ<15>
  VSS116  = GND
  DQ18_B  = M_F_CPU0_SB_DQ<18>
  VSS117  = GND
  DQ19_B  = M_F_CPU0_SB_DQ<19>
  VSS118  = GND
  \dqs7_b_c||tdqs7_b_c\  = M_F_CPU0_SB_DQS_DN<7>
  \dqs7_b_t||tdqs7_b_t\  = M_F_CPU0_SB_DQS_DP<7>
  VSS119  = GND
  DQ22_B  = M_F_CPU0_SB_DQ<22>
  VSS120  = GND
  DQ23_B  = M_F_CPU0_SB_DQ<23>
  VSS121  = GND
  DQ26_B  = M_F_CPU0_SB_DQ<26>
  VSS122  = GND
  DQ27_B  = M_F_CPU0_SB_DQ<27>
  VSS123  = GND
  \dqs8_b_c||tdqs8_b_c\  = M_F_CPU0_SB_DQS_DN<8>
  \dqs8_b_t||tdqs8_b_t\  = M_F_CPU0_SB_DQS_DP<8>
  VSS124  = GND
  DQ30_B  = M_F_CPU0_SB_DQ<30>
  VSS125  = GND
  DQ31_B  = M_F_CPU0_SB_DQ<31>
  VSS126  = GND
  G1  = GND
  G2  = GND
  G3  = GND

(kicad_pcb
	(version 20260206)
	(generator "pcbnew")
	(generator_version "10.0")
	(general
		(thickness 1.6)
		(legacy_teardrops no)
	)
	(paper "A4")
	(title_block
		(title "03242023_DA0F0TMBIJ0_F0T_Motherboard_J_brd_V01_OCP.brd")
		(comment 1 "Grand Teton / footprint 1952 of 6105 (J11), pads 183-228 of 291")
	)
	(layers
		(0 "F.Cu" signal "TOP")
		(4 "In1.Cu" signal "GND")
		(6 "In2.Cu" signal "IN1")
		(8 "In3.Cu" signal "GND1")
		(10 "In4.Cu" signal "IN2")
		(12 "In5.Cu" signal "GND2")
		(14 "In6.Cu" signal "IN3")
		(16 "In7.Cu" signal "GND3")
		(18 "In8.Cu" signal "VCC")
		(20 "In9.Cu" signal "VCC1")
		(22 "In10.Cu" signal "GND4")
		(24 "In11.Cu" signal "IN4")
		(26 "In12.Cu" signal "GND5")
		(28 "In13.Cu" signal "IN5")
		(30 "In14.Cu" signal "GND6")
		(32 "In15.Cu" signal "IN6")
		(34 "In16.Cu" signal "GND7")
		(2 "B.Cu" signal "BOTTOM")
		(9 "F.Adhes" user "F.Adhesive")
		(11 "B.Adhes" user "B.Adhesive")
		(13 "F.Paste" user "Package Geometry/Pastemask Top")
		(15 "B.Paste" user "Package Geometry/Pastemask Bottom")
		(5 "F.SilkS" user "Ref Des/Silkscreen Top")
		(7 "B.SilkS" user "Ref Des/Silkscreen Bottom")
		(1 "F.Mask" user "Board Geometry/Soldermask Top")
		(3 "B.Mask" user "Board Geometry/Soldermask Bottom")
		(17 "Dwgs.User" user "User.Drawings")
		(19 "Cmts.User" user "User.Comments")
		(21 "Eco1.User" user "User.Eco1")
		(23 "Eco2.User" user "User.Eco2")
		(25 "Edge.Cuts" user "Board Geometry/Outline")
		(27 "Margin" user)
		(31 "F.CrtYd" user "Package Geometry/Place Bound Top")
		(29 "B.CrtYd" user "Package Geometry/Place Bound Bottom")
		(35 "F.Fab" user "Ref Des/Assembly Top")
		(33 "B.Fab" user "Ref Des/Assembly Bottom")
	)
	(footprint ""
		(layer "F.Cu")
		(at 431.434748 -258.091686)
		(property "Reference" "J11"
			(at -3.683 -81.702148 0)
			(unlocked yes)
			(layer "F.SilkS")
			(effects
				(font
					(size 0.7874 0.5842)
					(thickness 0.1524)
				)
				(justify left)
			)
		)
		(property "Value" ""
			(at 0 0 0)
			(layer "F.Fab")
			(effects
				(font
					(size 1.27 1.27)
				)
			)
		)
		(duplicate_pad_numbers_are_jumpers no)
		(pad "183" smd rect
			(at 2.050034 -31.025084 270)
			(size 0.519938 1.4986)
			(layers "F.Cu" "F.Mask" "F.Paste")
			(net "M_F_CPU0_SA_DQ<23>")
		)
		(pad "184" smd rect
			(at 2.050034 -30.174946 270)
			(size 0.519938 1.4986)
			(layers "F.Cu" "F.Mask" "F.Paste")
			(net "GND")
		)
		(pad "185" smd rect
			(at 2.050034 -29.325062 270)
			(size 0.519938 1.4986)
			(layers "F.Cu" "F.Mask" "F.Paste")
			(net "M_F_CPU0_SA_DQ<26>")
		)
		(pad "186" smd rect
			(at 2.050034 -28.474924 270)
			(size 0.519938 1.4986)
			(layers "F.Cu" "F.Mask" "F.Paste")
			(net "GND")
		)
		(pad "187" smd rect
			(at 2.050034 -27.62504 270)
			(size 0.519938 1.4986)
			(layers "F.Cu" "F.Mask" "F.Paste")
			(net "M_F_CPU0_SA_DQ<27>")
		)
		(pad "188" smd rect
			(at 2.050034 -26.774902 270)
			(size 0.519938 1.4986)
			(layers "F.Cu" "F.Mask" "F.Paste")
			(net "GND")
		)
		(pad "189" smd rect
			(at 2.050034 -25.925018 270)
			(size 0.519938 1.4986)
			(layers "F.Cu" "F.Mask" "F.Paste")
			(net "M_F_CPU0_SA_DQS_DN<8>")
		)
		(pad "190" smd rect
			(at 2.050034 -25.07488 270)
			(size 0.519938 1.4986)
			(layers "F.Cu" "F.Mask" "F.Paste")
			(net "M_F_CPU0_SA_DQS_DP<8>")
		)
		(pad "191" smd rect
			(at 2.050034 -24.224996 270)
			(size 0.519938 1.4986)
			(layers "F.Cu" "F.Mask" "F.Paste")
			(net "GND")
		)
		(pad "192" smd rect
			(at 2.050034 -23.375112 270)
			(size 0.519938 1.4986)
			(layers "F.Cu" "F.Mask" "F.Paste")
			(net "M_F_CPU0_SA_DQ<30>")
		)
		(pad "193" smd rect
			(at 2.050034 -22.524974 270)
			(size 0.519938 1.4986)
			(layers "F.Cu" "F.Mask" "F.Paste")
			(net "GND")
		)
		(pad "194" smd rect
			(at 2.050034 -21.67509 270)
			(size 0.519938 1.4986)
			(layers "F.Cu" "F.Mask" "F.Paste")
			(net "M_F_CPU0_SA_DQ<31>")
		)
		(pad "195" smd rect
			(at 2.050034 -20.824952 270)
			(size 0.519938 1.4986)
			(layers "F.Cu" "F.Mask" "F.Paste")
			(net "GND")
		)
		(pad "196" smd rect
			(at 2.050034 -19.975068 270)
			(size 0.519938 1.4986)
			(layers "F.Cu" "F.Mask" "F.Paste")
			(net "M_F_CPU0_SA_CB<2>")
		)
		(pad "197" smd rect
			(at 2.050034 -19.12493 270)
			(size 0.519938 1.4986)
			(layers "F.Cu" "F.Mask" "F.Paste")
			(net "GND")
		)
		(pad "198" smd rect
			(at 2.050034 -18.275046 270)
			(size 0.519938 1.4986)
			(layers "F.Cu" "F.Mask" "F.Paste")
			(net "M_F_CPU0_SA_CB<3>")
		)
		(pad "199" smd rect
			(at 2.050034 -17.424908 270)
			(size 0.519938 1.4986)
			(layers "F.Cu" "F.Mask" "F.Paste")
			(net "GND")
		)
		(pad "200" smd rect
			(at 2.050034 -16.575024 270)
			(size 0.519938 1.4986)
			(layers "F.Cu" "F.Mask" "F.Paste")
			(net "M_F_CPU0_SA_DQS_DN<9>")
		)
		(pad "201" smd rect
			(at 2.050034 -15.724886 270)
			(size 0.519938 1.4986)
			(layers "F.Cu" "F.Mask" "F.Paste")
			(net "M_F_CPU0_SA_DQS_DP<9>")
		)
		(pad "202" smd rect
			(at 2.050034 -14.875002 270)
			(size 0.519938 1.4986)
			(layers "F.Cu" "F.Mask" "F.Paste")
			(net "GND")
		)
		(pad "203" smd rect
			(at 2.050034 -14.025118 270)
			(size 0.519938 1.4986)
			(layers "F.Cu" "F.Mask" "F.Paste")
			(net "M_F_CPU0_SA_CB<6>")
		)
		(pad "204" smd rect
			(at 2.050034 -13.17498 270)
			(size 0.519938 1.4986)
			(layers "F.Cu" "F.Mask" "F.Paste")
			(net "GND")
		)
		(pad "205" smd rect
			(at 2.050034 -12.325096 270)
			(size 0.519938 1.4986)
			(layers "F.Cu" "F.Mask" "F.Paste")
			(net "M_F_CPU0_SA_CB<7>")
		)
		(pad "206" smd rect
			(at 2.050034 -11.474958 270)
			(size 0.519938 1.4986)
			(layers "F.Cu" "F.Mask" "F.Paste")
			(net "GND")
		)
		(pad "207" smd rect
			(at 2.050034 -10.625074 270)
			(size 0.519938 1.4986)
			(layers "F.Cu" "F.Mask" "F.Paste")
			(net "RST_M_EF_CPU0_FPGA_N")
		)
		(pad "208" smd rect
			(at 2.050034 -9.774936 270)
			(size 0.519938 1.4986)
			(layers "F.Cu" "F.Mask" "F.Paste")
			(net "GND")
		)
		(pad "209" smd rect
			(at 2.050034 -8.925052 270)
			(size 0.519938 1.4986)
			(layers "F.Cu" "F.Mask" "F.Paste")
			(net "M_F_CPU0_SA_CS_N<1>")
		)
		(pad "210" smd rect
			(at 2.050034 -8.074914 270)
			(size 0.519938 1.4986)
			(layers "F.Cu" "F.Mask" "F.Paste")
			(net "GND")
		)
		(pad "211" smd rect
			(at 2.050034 -7.22503 270)
			(size 0.519938 1.4986)
			(layers "F.Cu" "F.Mask" "F.Paste")
			(net "M_F_CPU0_SA_CA<1>")
		)
		(pad "212" smd rect
			(at 2.050034 -6.374892 270)
			(size 0.519938 1.4986)
			(layers "F.Cu" "F.Mask" "F.Paste")
			(net "GND")
		)
		(pad "213" smd rect
			(at 2.050034 -5.525008 270)
			(size 0.519938 1.4986)
			(layers "F.Cu" "F.Mask" "F.Paste")
			(net "M_F_CPU0_SA_CA<3>")
		)
		(pad "214" smd rect
			(at 2.050034 -4.675124 270)
			(size 0.519938 1.4986)
			(layers "F.Cu" "F.Mask" "F.Paste")
			(net "GND")
		)
		(pad "215" smd rect
			(at 2.050034 -3.824986 270)
			(size 0.519938 1.4986)
			(layers "F.Cu" "F.Mask" "F.Paste")
			(net "M_F_CPU0_SA_CA<5>")
		)
		(pad "216" smd rect
			(at 2.050034 -2.975102 270)
			(size 0.519938 1.4986)
			(layers "F.Cu" "F.Mask" "F.Paste")
			(net "GND")
		)
		(pad "217" smd rect
			(at 2.050034 -2.124964 270)
			(size 0.519938 1.4986)
			(layers "F.Cu" "F.Mask" "F.Paste")
			(net "M_F_CPU0_CLK_DP<0>")
		)
		(pad "218" smd rect
			(at 2.050034 -1.27508 270)
			(size 0.519938 1.4986)
			(layers "F.Cu" "F.Mask" "F.Paste")
			(net "M_F_CPU0_CLK_DN<0>")
		)
		(pad "219" smd rect
			(at 2.050034 -0.424942 270)
			(size 0.519938 1.4986)
			(layers "F.Cu" "F.Mask" "F.Paste")
			(net "GND")
		)
		(pad "220" smd rect
			(at 2.050034 5.525008 270)
			(size 0.519938 1.4986)
			(layers "F.Cu" "F.Mask" "F.Paste")
			(net "TP_CHF_CPU0_DIMM1_FRU_4")
		)
		(pad "221" smd rect
			(at 2.050034 6.374892 270)
			(size 0.519938 1.4986)
			(layers "F.Cu" "F.Mask" "F.Paste")
			(net "M_F_CPU0_SB_CA<1>")
		)
		(pad "222" smd rect
			(at 2.050034 7.22503 270)
			(size 0.519938 1.4986)
			(layers "F.Cu" "F.Mask" "F.Paste")
			(net "GND")
		)
		(pad "223" smd rect
			(at 2.050034 8.074914 270)
			(size 0.519938 1.4986)
			(layers "F.Cu" "F.Mask" "F.Paste")
			(net "M_F_CPU0_SB_CA<3>")
		)
		(pad "224" smd rect
			(at 2.050034 8.925052 270)
			(size 0.519938 1.4986)
			(layers "F.Cu" "F.Mask" "F.Paste")
			(net "GND")
		)
		(pad "225" smd rect
			(at 2.050034 9.774936 270)
			(size 0.519938 1.4986)
			(layers "F.Cu" "F.Mask" "F.Paste")
			(net "M_F_CPU0_SB_CA<5>")
		)
		(pad "226" smd rect
			(at 2.050034 10.625074 270)
			(size 0.519938 1.4986)
			(layers "F.Cu" "F.Mask" "F.Paste")
			(net "GND")
		)
		(pad "227" smd rect
			(at 2.050034 11.474958 270)
			(size 0.519938 1.4986)
			(layers "F.Cu" "F.Mask" "F.Paste")
			(net "M_F_CPU0_SB_PAR")
		)
		(pad "228" smd rect
			(at 2.050034 12.325096 270)
			(size 0.519938 1.4986)
			(layers "F.Cu" "F.Mask" "F.Paste")
			(net "GND")
		)
	)
)
